(kicad_pcb
	(version 20260206)
	(generator "pcbnew")
	(generator_version "10.0")
	(general
		(thickness 1.6)
		(legacy_teardrops no)
	)
	(paper "A4")
	(title_block
		(title "v1-pdb — T6M_PDB_D_0927_0900.brd")
		(comment 1 "Open CloudServer (Microsoft) / footprints 76-85 of 321")
	)
	(layers
		(0 "F.Cu" signal "TOP")
		(4 "In1.Cu" signal "GND")
		(6 "In2.Cu" signal "IN1")
		(8 "In3.Cu" signal "VCC")
		(10 "In4.Cu" signal "VCC1")
		(12 "In5.Cu" signal "IN2")
		(14 "In6.Cu" signal "GND1")
		(2 "B.Cu" signal "BOTTOM")
		(9 "F.Adhes" user "F.Adhesive")
		(11 "B.Adhes" user "B.Adhesive")
		(13 "F.Paste" user "Package Geometry/Pastemask Top")
		(15 "B.Paste" user "Package Geometry/Pastemask Bottom")
		(5 "F.SilkS" user "Ref Des/Silkscreen Top")
		(7 "B.SilkS" user "Ref Des/Silkscreen Bottom")
		(1 "F.Mask" user "Board Geometry/Soldermask Top")
		(3 "B.Mask" user "Board Geometry/Soldermask Bottom")
		(17 "Dwgs.User" user "User.Drawings")
		(19 "Cmts.User" user "User.Comments")
		(21 "Eco1.User" user "User.Eco1")
		(23 "Eco2.User" user "User.Eco2")
		(25 "Edge.Cuts" user "Board Geometry/Outline")
		(27 "Margin" user)
		(31 "F.CrtYd" user "Package Geometry/Place Bound Top")
		(29 "B.CrtYd" user "Package Geometry/Place Bound Bottom")
		(35 "F.Fab" user "Ref Des/Assembly Top")
		(33 "B.Fab" user "Ref Des/Assembly Bottom")
	)
	(footprint ""
		(layer "F.Cu")
		(at 27.244802 -19.46402 90)
		(property "Reference" "R113"
			(at -3.094482 -0.932688 90)
			(unlocked yes)
			(layer "F.SilkS")
			(effects
				(font
					(size 0.7874 0.5842)
					(thickness 0.1524)
				)
				(justify left)
			)
		)
		(property "Value" ""
			(at 0 0 90)
			(layer "F.Fab")
			(effects
				(font
					(size 1.27 1.27)
				)
			)
		)
		(duplicate_pad_numbers_are_jumpers no)
		(fp_line
			(start 0.7874 -0.4064)
			(end 0.7874 0.4064)
			(stroke
				(width 0.1524)
				(type default)
			)
			(layer "F.SilkS")
		)
		(fp_line
			(start -0.7874 -0.4064)
			(end 0.7874 -0.4064)
			(stroke
				(width 0.1524)
				(type default)
			)
			(layer "F.SilkS")
		)
		(fp_line
			(start 0.7874 0.4064)
			(end -0.7874 0.4064)
			(stroke
				(width 0.1524)
				(type default)
			)
			(layer "F.SilkS")
		)
		(fp_line
			(start -0.7874 0.4064)
			(end -0.7874 -0.4064)
			(stroke
				(width 0.1524)
				(type default)
			)
			(layer "F.SilkS")
		)
		(fp_poly
			(pts
				(xy -0.508 0.2794) (xy -0.508 0.2286) (xy -0.635 0.2286) (xy -0.635 -0.254) (xy -0.5334 -0.254)
				(xy -0.5334 -0.2794) (xy 0.5334 -0.2794) (xy 0.5334 -0.254) (xy 0.635 -0.254) (xy 0.635 0.254) (xy 0.5334 0.254)
				(xy 0.5334 0.2794)
			)
			(stroke
				(width 0)
				(type default)
			)
			(fill no)
			(layer "F.CrtYd")
		)
		(pad "1" smd rect
			(at 0.40005 0 90)
			(size 0.4572 0.508)
			(layers "F.Cu" "F.Mask" "F.Paste")
			(net "PSU1_REMOTE_N")
		)
		(pad "2" smd rect
			(at -0.40005 0 90)
			(size 0.4572 0.508)
			(layers "F.Cu" "F.Mask" "F.Paste")
			(net "PSU1_REMOTE_R2_N")
		)
	)
	(footprint ""
		(layer "F.Cu")
		(at 91.399868 -508.96012)
		(property "Reference" "H24"
			(at -5.1308 -5.23113 0)
			(unlocked yes)
			(layer "F.SilkS")
			(effects
				(font
					(size 0.7874 0.5842)
					(thickness 0.1524)
				)
				(justify left)
			)
		)
		(property "Value" ""
			(at 0 0 0)
			(layer "F.Fab")
			(effects
				(font
					(size 1.27 1.27)
				)
			)
		)
		(duplicate_pad_numbers_are_jumpers no)
		(fp_circle
			(center 0 0)
			(end 4.826 0)
			(stroke
				(width 0.1524)
				(type default)
			)
			(fill no)
			(layer "F.SilkS")
		)
		(fp_circle
			(center 0 0)
			(end 4.826 0)
			(stroke
				(width 0.1524)
				(type default)
			)
			(fill no)
			(layer "B.SilkS")
		)
		(fp_poly
			(pts
				(arc
					(start 0 4.0132)
					(mid 0 -4.0132)
					(end 0 4.0132)
				)
			)
			(stroke
				(width 0)
				(type default)
			)
			(fill no)
			(layer "F.CrtYd")
		)
		(pad "" np_thru_hole circle
			(at 0 0)
			(size 8.001 8.001)
			(drill 8.001)
			(layers "*.Cu" "*.Mask")
			(clearance 0.381)
			(thermal_gap 0.381)
		)
		(zone
			(layers "F.Cu" "B.Cu" "In1.Cu" "In2.Cu" "In3.Cu" "In4.Cu" "In5.Cu" "In6.Cu")
			(hatch none 0.5)
			(connect_pads
				(clearance 0)
			)
			(min_thickness 0.25)
			(keepout
				(tracks not_allowed)
				(vias allowed)
				(pads allowed)
				(copperpour not_allowed)
				(footprints allowed)
			)
			(placement
				(enabled no)
				(sheetname "")
			)
			(fill
				(thermal_gap 0.5)
				(thermal_bridge_width 0.5)
				(island_removal_mode 0)
			)
			(polygon
				(pts
					(arc
						(start 91.399868 -504.43892)
						(mid 91.399868 -513.48132)
						(end 91.399868 -504.43892)
					)
				)
			)
		)
	)
	(footprint ""
		(layer "F.Cu")
		(at 39.437056 -287.977326 -90)
		(property "Reference" "R106"
			(at -1.168146 -0.000762 90)
			(unlocked yes)
			(layer "F.SilkS")
			(effects
				(font
					(size 0.7874 0.5842)
					(thickness 0.1524)
				)
				(justify left)
			)
		)
		(property "Value" ""
			(at 0 0 270)
			(layer "F.Fab")
			(effects
				(font
					(size 1.27 1.27)
				)
			)
		)
		(duplicate_pad_numbers_are_jumpers no)
		(fp_line
			(start -0.7874 0.4064)
			(end -0.7874 -0.4064)
			(stroke
				(width 0.1524)
				(type default)
			)
			(layer "F.SilkS")
		)
		(fp_line
			(start 0.7874 0.4064)
			(end -0.7874 0.4064)
			(stroke
				(width 0.1524)
				(type default)
			)
			(layer "F.SilkS")
		)
		(fp_line
			(start -0.7874 -0.4064)
			(end 0.7874 -0.4064)
			(stroke
				(width 0.1524)
				(type default)
			)
			(layer "F.SilkS")
		)
		(fp_line
			(start 0.7874 -0.4064)
			(end 0.7874 0.4064)
			(stroke
				(width 0.1524)
				(type default)
			)
			(layer "F.SilkS")
		)
		(fp_poly
			(pts
				(xy -0.508 0.2794) (xy -0.508 0.2286) (xy -0.635 0.2286) (xy -0.635 -0.254) (xy -0.5334 -0.254)
				(xy -0.5334 -0.2794) (xy 0.5334 -0.2794) (xy 0.5334 -0.254) (xy 0.635 -0.254) (xy 0.635 0.254) (xy 0.5334 0.254)
				(xy 0.5334 0.2794)
			)
			(stroke
				(width 0)
				(type default)
			)
			(fill no)
			(layer "F.CrtYd")
		)
		(pad "1" smd rect
			(at 0.40005 0 270)
			(size 0.4572 0.508)
			(layers "F.Cu" "F.Mask" "F.Paste")
			(net "PSU4_REMOTE_P")
		)
		(pad "2" smd rect
			(at -0.40005 0 270)
			(size 0.4572 0.508)
			(layers "F.Cu" "F.Mask" "F.Paste")
			(net "PSU4_REMOTE_R_P")
		)
	)
	(footprint ""
		(layer "F.Cu")
		(at 71.423022 -60.163456 -90)
		(property "Reference" "C10"
			(at -2.559304 0.082804 90)
			(unlocked yes)
			(layer "F.SilkS")
			(effects
				(font
					(size 0.7874 0.5842)
					(thickness 0.1524)
				)
				(justify left)
			)
		)
		(property "Value" ""
			(at 0 0 270)
			(layer "F.Fab")
			(effects
				(font
					(size 1.27 1.27)
				)
			)
		)
		(duplicate_pad_numbers_are_jumpers no)
		(fp_line
			(start -0.7874 0.4064)
			(end -0.7874 -0.4064)
			(stroke
				(width 0.1524)
				(type default)
			)
			(layer "F.SilkS")
		)
		(fp_line
			(start 0.7874 0.4064)
			(end -0.7874 0.4064)
			(stroke
				(width 0.1524)
				(type default)
			)
			(layer "F.SilkS")
		)
		(fp_line
			(start 0 0.381)
			(end 0 -0.381)
			(stroke
				(width 0.1524)
				(type default)
			)
			(layer "F.SilkS")
		)
		(fp_line
			(start -0.7874 -0.4064)
			(end 0.7874 -0.4064)
			(stroke
				(width 0.1524)
				(type default)
			)
			(layer "F.SilkS")
		)
		(fp_line
			(start 0.7874 -0.4064)
			(end 0.7874 0.4064)
			(stroke
				(width 0.1524)
				(type default)
			)
			(layer "F.SilkS")
		)
		(fp_poly
			(pts
				(xy -0.5334 0.254) (xy -0.635 0.254) (xy -0.635 0.2286) (xy -0.635 -0.254) (xy -0.5334 -0.254) (xy -0.5334 -0.2794)
				(xy 0.5334 -0.2794) (xy 0.5334 -0.254) (xy 0.635 -0.254) (xy 0.635 0.254) (xy 0.5334 0.254) (xy 0.5334 0.2794)
				(xy -0.508 0.2794) (xy -0.5334 0.2794)
			)
			(stroke
				(width 0)
				(type default)
			)
			(fill no)
			(layer "F.CrtYd")
		)
		(pad "1" smd rect
			(at 0.40005 0 270)
			(size 0.4572 0.508)
			(layers "F.Cu" "F.Mask" "F.Paste")
			(net "P12V")
		)
		(pad "2" smd rect
			(at -0.40005 0 270)
			(size 0.4572 0.508)
			(layers "F.Cu" "F.Mask" "F.Paste")
			(net "GND")
		)
	)
	(footprint ""
		(layer "F.Cu")
		(at 45.911516 -260.355588 180)
		(property "Reference" "R103"
			(at 4.696206 0.233172 0)
			(unlocked yes)
			(layer "F.SilkS")
			(effects
				(font
					(size 0.7874 0.5842)
					(thickness 0.1524)
				)
				(justify left)
			)
		)
		(property "Value" ""
			(at 0 0 180)
			(layer "F.Fab")
			(effects
				(font
					(size 1.27 1.27)
				)
			)
		)
		(duplicate_pad_numbers_are_jumpers no)
		(fp_line
			(start 0.7874 0.4064)
			(end -0.7874 0.4064)
			(stroke
				(width 0.1524)
				(type default)
			)
			(layer "F.SilkS")
		)
		(fp_line
			(start 0.7874 -0.4064)
			(end 0.7874 0.4064)
			(stroke
				(width 0.1524)
				(type default)
			)
			(layer "F.SilkS")
		)
		(fp_line
			(start -0.7874 0.4064)
			(end -0.7874 -0.4064)
			(stroke
				(width 0.1524)
				(type default)
			)
			(layer "F.SilkS")
		)
		(fp_line
			(start -0.7874 -0.4064)
			(end 0.7874 -0.4064)
			(stroke
				(width 0.1524)
				(type default)
			)
			(layer "F.SilkS")
		)
		(fp_poly
			(pts
				(xy -0.508 0.2794) (xy -0.508 0.2286) (xy -0.635 0.2286) (xy -0.635 -0.254) (xy -0.5334 -0.254)
				(xy -0.5334 -0.2794) (xy 0.5334 -0.2794) (xy 0.5334 -0.254) (xy 0.635 -0.254) (xy 0.635 0.254) (xy 0.5334 0.254)
				(xy 0.5334 0.2794)
			)
			(stroke
				(width 0)
				(type default)
			)
			(fill no)
			(layer "F.CrtYd")
		)
		(pad "1" smd rect
			(at 0.40005 0 180)
			(size 0.4572 0.508)
			(layers "F.Cu" "F.Mask" "F.Paste")
			(net "PSU5_REMOTE_R_N")
		)
		(pad "2" smd rect
			(at -0.40005 0 180)
			(size 0.4572 0.508)
			(layers "F.Cu" "F.Mask" "F.Paste")
			(net "GND")
		)
	)
	(footprint ""
		(layer "F.Cu")
		(at 26.226008 -450.980556)
		(property "Reference" "R82"
			(at -3.597402 -0.121666 0)
			(unlocked yes)
			(layer "F.SilkS")
			(effects
				(font
					(size 0.7874 0.5842)
					(thickness 0.1524)
				)
				(justify left)
			)
		)
		(property "Value" ""
			(at 0 0 0)
			(layer "F.Fab")
			(effects
				(font
					(size 1.27 1.27)
				)
			)
		)
		(duplicate_pad_numbers_are_jumpers no)
		(fp_line
			(start -0.7874 -0.4064)
			(end 0.7874 -0.4064)
			(stroke
				(width 0.1524)
				(type default)
			)
			(layer "F.SilkS")
		)
		(fp_line
			(start -0.7874 0.4064)
			(end -0.7874 -0.4064)
			(stroke
				(width 0.1524)
				(type default)
			)
			(layer "F.SilkS")
		)
		(fp_line
			(start 0.7874 -0.4064)
			(end 0.7874 0.4064)
			(stroke
				(width 0.1524)
				(type default)
			)
			(layer "F.SilkS")
		)
		(fp_line
			(start 0.7874 0.4064)
			(end -0.7874 0.4064)
			(stroke
				(width 0.1524)
				(type default)
			)
			(layer "F.SilkS")
		)
		(fp_poly
			(pts
				(xy -0.508 0.2794) (xy -0.508 0.2286) (xy -0.635 0.2286) (xy -0.635 -0.254) (xy -0.5334 -0.254)
				(xy -0.5334 -0.2794) (xy 0.5334 -0.2794) (xy 0.5334 -0.254) (xy 0.635 -0.254) (xy 0.635 0.254) (xy 0.5334 0.254)
				(xy 0.5334 0.2794)
			)
			(stroke
				(width 0)
				(type default)
			)
			(fill no)
			(layer "F.CrtYd")
		)
		(pad "1" smd rect
			(at 0.40005 0)
			(size 0.4572 0.508)
			(layers "F.Cu" "F.Mask" "F.Paste")
			(net "PSU6_PS_KILL")
		)
		(pad "2" smd rect
			(at -0.40005 0)
			(size 0.4572 0.508)
			(layers "F.Cu" "F.Mask" "F.Paste")
			(net "P12V_STBY")
		)
	)
	(footprint ""
		(layer "F.Cu")
		(at 50.743612 -151.92502 180)
		(property "Reference" "CE8"
			(at -4.261612 -1.5494 0)
			(unlocked yes)
			(layer "F.SilkS")
			(effects
				(font
					(size 0.7874 0.5842)
					(thickness 0.1524)
				)
				(justify left)
			)
		)
		(property "Value" ""
			(at 0 0 180)
			(layer "F.Fab")
			(effects
				(font
					(size 1.27 1.27)
				)
			)
		)
		(duplicate_pad_numbers_are_jumpers no)
		(fp_line
			(start 0 -4.2672)
			(end 0 4.2672)
			(stroke
				(width 0.1524)
				(type default)
			)
			(layer "F.SilkS")
		)
		(fp_circle
			(center 0 0)
			(end -4.2672 0)
			(stroke
				(width 0.1524)
				(type default)
			)
			(fill no)
			(layer "F.SilkS")
		)
		(fp_poly
			(pts
				(arc
					(start 0 -4.2672)
					(mid 4.2672 0)
					(end 0 4.2672)
				)
			)
			(stroke
				(width 0)
				(type default)
			)
			(fill yes)
			(layer "F.SilkS")
		)
		(fp_poly
			(pts
				(xy -2.5146 -0.762) (xy -0.9906 -0.762) (xy -0.9906 0.762) (xy -2.5146 0.762)
			)
			(stroke
				(width 0)
				(type default)
			)
			(fill no)
			(layer "B.CrtYd")
		)
		(fp_poly
			(pts
				(arc
					(start 1.7526 0.762)
					(mid 2.291415 -0.538815)
					(end 0.9906 0)
				)
				(arc
					(start 0.9906 0.0254)
					(mid 1.206345 0.546255)
					(end 1.7272 0.762)
				)
			)
			(stroke
				(width 0)
				(type default)
			)
			(fill no)
			(layer "B.CrtYd")
		)
		(fp_poly
			(pts
				(arc
					(start -4.2672 0)
					(mid 4.2672 0)
					(end -4.2672 0)
				)
			)
			(stroke
				(width 0)
				(type default)
			)
			(fill no)
			(layer "F.CrtYd")
		)
		(fp_circle
			(center 0 0)
			(end -4.2672 0)
			(stroke
				(width 0.1)
				(type default)
			)
			(fill no)
			(layer "F.Fab")
		)
		(fp_text user "+"
			(at -4.996688 -2.849372 180)
			(unlocked yes)
			(layer "F.SilkS")
			(effects
				(font
					(size 0.7874 0.5842)
					(thickness 0.1524)
				)
				(justify left)
			)
		)
		(fp_text user "+"
			(at -5.6642 -0.34925 180)
			(unlocked yes)
			(layer "F.Fab")
			(effects
				(font
					(size 1.905 1.4224)
					(thickness 0.000001)
				)
				(justify left)
			)
		)
		(pad "1" thru_hole rect
			(at -1.75006 0 180)
			(size 1.397 1.397)
			(drill 0.9144)
			(layers "*.Cu" "*.Mask")
			(remove_unused_layers no)
			(net "P12V")
			(clearance 0.0127)
			(thermal_gap 0.0127)
			(padstack
				(mode front_inner_back)
				(layer "Inner"
					(shape circle)
					(size 1.397 1.397)
					(clearance 0.0127)
				)
				(layer "B.Cu"
					(shape rect)
					(size 1.397 1.397)
					(clearance 0.0127)
				)
			)
		)
		(pad "2" thru_hole circle
			(at 1.75006 0 180)
			(size 1.397 1.397)
			(drill 0.9144)
			(layers "*.Cu" "*.Mask")
			(remove_unused_layers no)
			(net "GND")
			(clearance 0.0127)
			(thermal_gap 0.0127)
		)
	)
	(footprint ""
		(layer "F.Cu")
		(at 26.226008 -452.257668)
		(property "Reference" "R83"
			(at -3.597402 -0.121666 0)
			(unlocked yes)
			(layer "F.SilkS")
			(effects
				(font
					(size 0.7874 0.5842)
					(thickness 0.1524)
				)
				(justify left)
			)
		)
		(property "Value" ""
			(at 0 0 0)
			(layer "F.Fab")
			(effects
				(font
					(size 1.27 1.27)
				)
			)
		)
		(duplicate_pad_numbers_are_jumpers no)
		(fp_line
			(start -0.7874 -0.4064)
			(end 0.7874 -0.4064)
			(stroke
				(width 0.1524)
				(type default)
			)
			(layer "F.SilkS")
		)
		(fp_line
			(start -0.7874 0.4064)
			(end -0.7874 -0.4064)
			(stroke
				(width 0.1524)
				(type default)
			)
			(layer "F.SilkS")
		)
		(fp_line
			(start 0.7874 -0.4064)
			(end 0.7874 0.4064)
			(stroke
				(width 0.1524)
				(type default)
			)
			(layer "F.SilkS")
		)
		(fp_line
			(start 0.7874 0.4064)
			(end -0.7874 0.4064)
			(stroke
				(width 0.1524)
				(type default)
			)
			(layer "F.SilkS")
		)
		(fp_poly
			(pts
				(xy -0.508 0.2794) (xy -0.508 0.2286) (xy -0.635 0.2286) (xy -0.635 -0.254) (xy -0.5334 -0.254)
				(xy -0.5334 -0.2794) (xy 0.5334 -0.2794) (xy 0.5334 -0.254) (xy 0.635 -0.254) (xy 0.635 0.254) (xy 0.5334 0.254)
				(xy 0.5334 0.2794)
			)
			(stroke
				(width 0)
				(type default)
			)
			(fill no)
			(layer "F.CrtYd")
		)
		(pad "1" smd rect
			(at 0.40005 0)
			(size 0.4572 0.508)
			(layers "F.Cu" "F.Mask" "F.Paste")
			(net "PSU6_PS_KILL")
		)
		(pad "2" smd rect
			(at -0.40005 0)
			(size 0.4572 0.508)
			(layers "F.Cu" "F.Mask" "F.Paste")
			(net "GND")
		)
	)
	(footprint ""
		(layer "F.Cu")
		(at 72.087232 -327.030588 -90)
		(property "Reference" "C50"
			(at -3.323844 -0.030226 90)
			(unlocked yes)
			(layer "F.SilkS")
			(effects
				(font
					(size 0.7874 0.5842)
					(thickness 0.1524)
				)
			)
		)
		(property "Value" ""
			(at 0 0 270)
			(layer "F.Fab")
			(effects
				(font
					(size 1.27 1.27)
				)
			)
		)
		(duplicate_pad_numbers_are_jumpers no)
		(fp_line
			(start -1.2954 0.5842)
			(end -1.2954 -0.5842)
			(stroke
				(width 0.1524)
				(type default)
			)
			(layer "F.SilkS")
		)
		(fp_line
			(start 1.2954 0.5842)
			(end -1.2954 0.5842)
			(stroke
				(width 0.1524)
				(type default)
			)
			(layer "F.SilkS")
		)
		(fp_line
			(start -1.2954 -0.5842)
			(end 1.2954 -0.5842)
			(stroke
				(width 0.1524)
				(type default)
			)
			(layer "F.SilkS")
		)
		(fp_line
			(start 0 -0.5842)
			(end 0 0.5842)
			(stroke
				(width 0.1524)
				(type default)
			)
			(layer "F.SilkS")
		)
		(fp_line
			(start 1.2954 -0.5842)
			(end 1.2954 0.5842)
			(stroke
				(width 0.1524)
				(type default)
			)
			(layer "F.SilkS")
		)
		(fp_poly
			(pts
				(xy 0.8636 -0.4572) (xy 0.8636 -0.3556) (xy 1.143 -0.3556) (xy 1.143 0.3556) (xy 0.8636 0.3556)
				(xy 0.8636 0.4572) (xy -0.8636 0.4572) (xy -0.8636 0.3556) (xy -1.143 0.3556) (xy -1.143 -0.3556)
				(xy -0.8636 -0.3556) (xy -0.8636 -0.4572)
			)
			(stroke
				(width 0)
				(type default)
			)
			(fill no)
			(layer "F.CrtYd")
		)
		(fp_line
			(start -0.884936 0.504952)
			(end -0.884936 -0.504952)
			(stroke
				(width 0.1)
				(type default)
			)
			(layer "F.Fab")
		)
		(fp_line
			(start 0.884936 0.504952)
			(end -0.884936 0.504952)
			(stroke
				(width 0.1)
				(type default)
			)
			(layer "F.Fab")
		)
		(fp_line
			(start -0.884936 -0.504952)
			(end 0.884936 -0.504952)
			(stroke
				(width 0.1)
				(type default)
			)
			(layer "F.Fab")
		)
		(fp_line
			(start 0.884936 -0.504952)
			(end 0.884936 0.504952)
			(stroke
				(width 0.1)
				(type default)
			)
			(layer "F.Fab")
		)
		(pad "1" smd rect
			(at 0.7366 0)
			(size 0.7112 0.8128)
			(layers "F.Cu" "F.Mask" "F.Paste")
			(net "P12V")
		)
		(pad "2" smd rect
			(at -0.7366 0)
			(size 0.7112 0.8128)
			(layers "F.Cu" "F.Mask" "F.Paste")
			(net "GND")
		)
	)
	(footprint ""
		(layer "F.Cu")
		(at 13.438124 -322.972176 180)
		(property "Reference" "R147"
			(at -1.094232 -0.065024 0)
			(unlocked yes)
			(layer "F.SilkS")
			(effects
				(font
					(size 0.7874 0.5842)
					(thickness 0.1524)
				)
				(justify left)
			)
		)
		(property "Value" ""
			(at 0 0 180)
			(layer "F.Fab")
			(effects
				(font
					(size 1.27 1.27)
				)
			)
		)
		(duplicate_pad_numbers_are_jumpers no)
		(fp_line
			(start 0.7874 0.4064)
			(end -0.7874 0.4064)
			(stroke
				(width 0.1524)
				(type default)
			)
			(layer "F.SilkS")
		)
		(fp_line
			(start 0.7874 -0.4064)
			(end 0.7874 0.4064)
			(stroke
				(width 0.1524)
				(type default)
			)
			(layer "F.SilkS")
		)
		(fp_line
			(start -0.7874 0.4064)
			(end -0.7874 -0.4064)
			(stroke
				(width 0.1524)
				(type default)
			)
			(layer "F.SilkS")
		)
		(fp_line
			(start -0.7874 -0.4064)
			(end 0.7874 -0.4064)
			(stroke
				(width 0.1524)
				(type default)
			)
			(layer "F.SilkS")
		)
		(fp_poly
			(pts
				(xy -0.508 0.2794) (xy -0.508 0.2286) (xy -0.635 0.2286) (xy -0.635 -0.254) (xy -0.5334 -0.254)
				(xy -0.5334 -0.2794) (xy 0.5334 -0.2794) (xy 0.5334 -0.254) (xy 0.635 -0.254) (xy 0.635 0.254) (xy 0.5334 0.254)
				(xy 0.5334 0.2794)
			)
			(stroke
				(width 0)
				(type default)
			)
			(fill no)
			(layer "F.CrtYd")
		)
		(pad "1" smd rect
			(at 0.40005 0 180)
			(size 0.4572 0.508)
			(layers "F.Cu" "F.Mask" "F.Paste")
			(net "FAN6_TACH")
		)
		(pad "2" smd rect
			(at -0.40005 0 180)
			(size 0.4572 0.508)
			(layers "F.Cu" "F.Mask" "F.Paste")
			(net "P12V")
		)
	)
)
